# Lightning  PTB_Stackup.xlsx — Wiwynn (pcb-stackup)
|  |  |  |  |  |  |  |  |  |  |  | Single Ended Type(mil) |  |  |  |
|  |  |  |  |  |  |  |  |  |  | Imp | 50 |  |  |  |
|  |  |  |  |  |  |  |  |  |  | Variation | Inner /Outer ±5Ω |  |  |  |
|  |  |  |  |  |  |  |  |  |  | Bus | MISC |  |  |  |
|  |  |  |  |  |  |  |  |  |  | Type | SE |  |  |  |
| Layer |  |  |  | Thickness |  | Glass style | Er |  | Df(1G) | Layers | All |  |  |  |
|  |  |  | Cu oz | Wiwynn | Vender |  | Wiwynn | Vender |  |  | Wiwynn |  | Vender |  |
|  | Mask |  |  | 0.5 |  |  | 3.8 |  |  |  | Width | Imp | Width | Imp |
| Top | Signal |  | 0.5 oz + plating | 1.7 |  |  |  |  |  | S1 | 5.5 |  |  |  |
|  | Prepreg |  |  | 3.5 |  |  | 4 |  |  |  |  |  |  |  |
| L2 | PWR | GND | 1 oz | 2.6 |  |  |  |  |  | P2 | Reference layer |  | Reference layer |  |
|  | Core |  |  | 47 |  |  | 4.5 |  |  |  |  |  |  |  |
| L3 | PWR | GND | 1 oz | 2.6 |  |  |  |  |  | P3 | Reference layer |  | Reference layer |  |
|  | Prepreg |  |  | 3.5 |  |  | 4 |  |  |  |  |  |  |  |
| Bottom | Signal |  | 0.5 oz + plating | 1.7 |  |  |  |  |  | S4 | 5.5 |  |  |  |
|  | Mask |  |  | 0.5 |  |  | 3.8 |  |  |  |  |  |  |  |
| Thickness requirement: 1.62±10% mm |  |  | mil | 63.6 |  | +/-10% |  |  |  |  |  |  |  |  |
|  |  |  | mm | 1.6154432308864619 |  |  |  |  |  |  |  |  |  |  |
